# S9S_MB_2U (Grand Teton) — schematic netlist excerpt (pin names and nets, part order shuffled) for the footprints in the layout excerpt that follows; sources: Cadence DE-HDL packaged netlist, KiCad conversion of 03242023_DA0F0TMBIJ0_F0T_Motherboard_J_brd_V01_OCP.brd

R940  Q_RES  10K 1% CHIP  pkg 0402LF  page 115 : A = P3V3_AUX ; B = PWRGD_FAIL_CPU0_AB_R1
R3936  Q_RES  4.7K 1% CHIP  pkg 0402LF  page 301 : A = HSC_VDD ; B = HSC_D_OC

(kicad_pcb
	(version 20260206)
	(generator "pcbnew")
	(generator_version "10.0")
	(general
		(thickness 1.6)
		(legacy_teardrops no)
	)
	(paper "A4")
	(title_block
		(title "03242023_DA0F0TMBIJ0_F0T_Motherboard_J_brd_V01_OCP.brd")
		(comment 1 "Grand Teton / footprints 4167-4168 of 6105")
	)
	(layers
		(0 "F.Cu" signal "TOP")
		(4 "In1.Cu" signal "GND")
		(6 "In2.Cu" signal "IN1")
		(8 "In3.Cu" signal "GND1")
		(10 "In4.Cu" signal "IN2")
		(12 "In5.Cu" signal "GND2")
		(14 "In6.Cu" signal "IN3")
		(16 "In7.Cu" signal "GND3")
		(18 "In8.Cu" signal "VCC")
		(20 "In9.Cu" signal "VCC1")
		(22 "In10.Cu" signal "GND4")
		(24 "In11.Cu" signal "IN4")
		(26 "In12.Cu" signal "GND5")
		(28 "In13.Cu" signal "IN5")
		(30 "In14.Cu" signal "GND6")
		(32 "In15.Cu" signal "IN6")
		(34 "In16.Cu" signal "GND7")
		(2 "B.Cu" signal "BOTTOM")
		(9 "F.Adhes" user "F.Adhesive")
		(11 "B.Adhes" user "B.Adhesive")
		(13 "F.Paste" user "Package Geometry/Pastemask Top")
		(15 "B.Paste" user "Package Geometry/Pastemask Bottom")
		(5 "F.SilkS" user "Ref Des/Silkscreen Top")
		(7 "B.SilkS" user "Ref Des/Silkscreen Bottom")
		(1 "F.Mask" user "Board Geometry/Soldermask Top")
		(3 "B.Mask" user "Board Geometry/Soldermask Bottom")
		(17 "Dwgs.User" user "User.Drawings")
		(19 "Cmts.User" user "User.Comments")
		(21 "Eco1.User" user "User.Eco1")
		(23 "Eco2.User" user "User.Eco2")
		(25 "Edge.Cuts" user "Board Geometry/Outline")
		(27 "Margin" user)
		(31 "F.CrtYd" user "Package Geometry/Place Bound Top")
		(29 "B.CrtYd" user "Package Geometry/Place Bound Bottom")
		(35 "F.Fab" user "Ref Des/Assembly Top")
		(33 "B.Fab" user "Ref Des/Assembly Bottom")
	)
	(footprint ""
		(layer "B.Cu")
		(at 310.843422 -316.328044 90)
		(property "Reference" "R940"
			(at 0 0 90)
			(layer "B.SilkS")
			(hide yes)
			(effects
				(font
					(size 1.27 1.27)
				)
				(justify mirror)
			)
		)
		(property "Value" ""
			(at 0 0 90)
			(layer "B.Fab")
			(effects
				(font
					(size 1.27 1.27)
				)
				(justify mirror)
			)
		)
		(duplicate_pad_numbers_are_jumpers no)
		(fp_line
			(start 0.7874 -0.4064)
			(end -0.7874 -0.4064)
			(stroke
				(width 0.1524)
				(type default)
			)
			(layer "B.SilkS")
		)
		(fp_line
			(start -0.7874 -0.4064)
			(end -0.7874 0.4064)
			(stroke
				(width 0.1524)
				(type default)
			)
			(layer "B.SilkS")
		)
		(fp_line
			(start 0.7874 0.4064)
			(end 0.7874 -0.4064)
			(stroke
				(width 0.1524)
				(type default)
			)
			(layer "B.SilkS")
		)
		(fp_line
			(start -0.7874 0.4064)
			(end 0.7874 0.4064)
			(stroke
				(width 0.1524)
				(type default)
			)
			(layer "B.SilkS")
		)
		(fp_line
			(start 0.67945 -0.305054)
			(end 0.12065 -0.305054)
			(stroke
				(width 0.1)
				(type default)
			)
			(layer "B.Fab")
		)
		(fp_line
			(start 0.12065 -0.305054)
			(end 0.12065 -0.2794)
			(stroke
				(width 0.1)
				(type default)
			)
			(layer "B.Fab")
		)
		(fp_line
			(start -0.12065 -0.3048)
			(end -0.67945 -0.3048)
			(stroke
				(width 0.1)
				(type default)
			)
			(layer "B.Fab")
		)
		(fp_line
			(start -0.67945 -0.3048)
			(end -0.67945 0.3048)
			(stroke
				(width 0.1)
				(type default)
			)
			(layer "B.Fab")
		)
		(fp_line
			(start 0.12065 -0.2794)
			(end -0.12065 -0.2794)
			(stroke
				(width 0.1)
				(type default)
			)
			(layer "B.Fab")
		)
		(fp_line
			(start -0.12065 -0.2794)
			(end -0.12065 -0.3048)
			(stroke
				(width 0.1)
				(type default)
			)
			(layer "B.Fab")
		)
		(fp_line
			(start 0.12065 0.2794)
			(end 0.12065 0.3048)
			(stroke
				(width 0.1)
				(type default)
			)
			(layer "B.Fab")
		)
		(fp_line
			(start -0.120396 0.2794)
			(end 0.12065 0.2794)
			(stroke
				(width 0.1)
				(type default)
			)
			(layer "B.Fab")
		)
		(fp_line
			(start 0.67945 0.3048)
			(end 0.67945 -0.305054)
			(stroke
				(width 0.1)
				(type default)
			)
			(layer "B.Fab")
		)
		(fp_line
			(start 0.12065 0.3048)
			(end 0.67945 0.3048)
			(stroke
				(width 0.1)
				(type default)
			)
			(layer "B.Fab")
		)
		(fp_line
			(start -0.120396 0.3048)
			(end -0.120396 0.2794)
			(stroke
				(width 0.1)
				(type default)
			)
			(layer "B.Fab")
		)
		(fp_line
			(start -0.67945 0.3048)
			(end -0.120396 0.3048)
			(stroke
				(width 0.1)
				(type default)
			)
			(layer "B.Fab")
		)
		(pad "1" smd circle
			(at 0.40005 0 270)
			(size 0 0)
			(layers "B.Cu" "B.Mask" "B.Paste")
			(net "P3V3_AUX")
		)
		(pad "2" smd circle
			(at -0.40005 0 270)
			(size 0 0)
			(layers "B.Cu" "B.Mask" "B.Paste")
			(net "PWRGD_FAIL_CPU0_AB_R1")
		)
	)
	(footprint ""
		(layer "B.Cu")
		(at 192.052448 -400.609562 180)
		(property "Reference" "R3936"
			(at 0 0 0)
			(layer "B.SilkS")
			(hide yes)
			(effects
				(font
					(size 1.27 1.27)
				)
				(justify mirror)
			)
		)
		(property "Value" ""
			(at 0 0 0)
			(layer "B.Fab")
			(effects
				(font
					(size 1.27 1.27)
				)
				(justify mirror)
			)
		)
		(duplicate_pad_numbers_are_jumpers no)
		(fp_line
			(start 0.7874 0.4064)
			(end 0.7874 -0.4064)
			(stroke
				(width 0.1524)
				(type default)
			)
			(layer "B.SilkS")
		)
		(fp_line
			(start 0.7874 -0.4064)
			(end -0.7874 -0.4064)
			(stroke
				(width 0.1524)
				(type default)
			)
			(layer "B.SilkS")
		)
		(fp_line
			(start -0.7874 0.4064)
			(end 0.7874 0.4064)
			(stroke
				(width 0.1524)
				(type default)
			)
			(layer "B.SilkS")
		)
		(fp_line
			(start -0.7874 -0.4064)
			(end -0.7874 0.4064)
			(stroke
				(width 0.1524)
				(type default)
			)
			(layer "B.SilkS")
		)
		(fp_line
			(start 0.67945 0.3048)
			(end 0.67945 -0.305054)
			(stroke
				(width 0.1)
				(type default)
			)
			(layer "B.Fab")
		)
		(fp_line
			(start 0.67945 -0.305054)
			(end 0.12065 -0.305054)
			(stroke
				(width 0.1)
				(type default)
			)
			(layer "B.Fab")
		)
		(fp_line
			(start 0.12065 0.3048)
			(end 0.67945 0.3048)
			(stroke
				(width 0.1)
				(type default)
			)
			(layer "B.Fab")
		)
		(fp_line
			(start 0.12065 0.2794)
			(end 0.12065 0.3048)
			(stroke
				(width 0.1)
				(type default)
			)
			(layer "B.Fab")
		)
		(fp_line
			(start 0.12065 -0.2794)
			(end -0.12065 -0.2794)
			(stroke
				(width 0.1)
				(type default)
			)
			(layer "B.Fab")
		)
		(fp_line
			(start 0.12065 -0.305054)
			(end 0.12065 -0.2794)
			(stroke
				(width 0.1)
				(type default)
			)
			(layer "B.Fab")
		)
		(fp_line
			(start -0.120396 0.3048)
			(end -0.120396 0.2794)
			(stroke
				(width 0.1)
				(type default)
			)
			(layer "B.Fab")
		)
		(fp_line
			(start -0.120396 0.2794)
			(end 0.12065 0.2794)
			(stroke
				(width 0.1)
				(type default)
			)
			(layer "B.Fab")
		)
		(fp_line
			(start -0.12065 -0.2794)
			(end -0.12065 -0.3048)
			(stroke
				(width 0.1)
				(type default)
			)
			(layer "B.Fab")
		)
		(fp_line
			(start -0.12065 -0.3048)
			(end -0.67945 -0.3048)
			(stroke
				(width 0.1)
				(type default)
			)
			(layer "B.Fab")
		)
		(fp_line
			(start -0.67945 0.3048)
			(end -0.120396 0.3048)
			(stroke
				(width 0.1)
				(type default)
			)
			(layer "B.Fab")
		)
		(fp_line
			(start -0.67945 -0.3048)
			(end -0.67945 0.3048)
			(stroke
				(width 0.1)
				(type default)
			)
			(layer "B.Fab")
		)
		(pad "1" smd circle
			(at 0.40005 0)
			(size 0 0)
			(layers "B.Cu" "B.Mask" "B.Paste")
			(net "HSC_VDD")
		)
		(pad "2" smd circle
			(at -0.40005 0)
			(size 0 0)
			(layers "B.Cu" "B.Mask" "B.Paste")
			(net "HSC_D_OC")
		)
	)
)
